FILE_TYPE = CONNECTIVITY;
{Allegro Design Entry HDL 17.4-2019 S026 (4007227) 1/17/2022}
"PAGE_NUMBER" = 377;
0"NC";
1"GND\g";
2"GND\g";
3"GND\g";
4"SMB_RT_CPU0_P0_ROM_MUX_1D_SDA";
5"SMB_RT_CPU0_P1_ROM_MUX_1D_SDA";
6"SMB_RT_CPU0_P3_ROM_MUX_1D_SDA";
7"SMB_RT_CPU0_P3_ROM_MUX_1D_SCL";
8"P1V8_CPU1_RT_1D\g";
9"SMB_RT_CPU1_P1_ROM_MUX_2D_R_SCL";
10"SMB_RT_CPU1_P2_ROM_MUX_1D_SCL";
11"SMB_RT_CPU1_P2_ROM_MUX_1D_SDA";
12"SMB_RT_CPU0_P0_ROM_MUX_2D_R_SDA";
13"P1V8_CPU0_RT_1D\g";
14"SMB_RT_CPU0_P1_ROM_MUX_1D_SCL";
15"SMB_RT_CPU0_P2_ROM_MUX_1D_SCL";
16"P1V8_CPU0_RT_1D\g";
17"SMB_RT_CPU0_P0_ROM_MUX_2D_R_SCL";
18"P1V8_CPU1_RT_1D\g";
19"SMB_RT_CPU1_P3_ROM_MUX_1D_SCL";
20"GND\g";
21"P1V8_CPU0_RT_1D\g";
22"P1V8_AUX\g";
23"P1V8_CPU1_RT_1D\g";
24"P1V8_AUX\g";
25"SMB_RT_CPU1_P0_ROM_MUX_1D_SDA";
26"SMB_RT_CPU1_P0_ROM_MUX_1D_SCL";
27"SMB_RT_CPU1_P1_ROM_MUX_1D_SDA";
28"SMB_RT_CPU1_P1_ROM_MUX_1D_SCL";
29"SMB_RT_CPU1_P3_ROM_MUX_1D_SDA";
30"SMB_RT_CPU0_P0_ROM_MUX_1D_SCL";
31"SMB_RT_CPU0_P2_ROM_MUX_1D_SDA";
32"SMB_RT_CPU0_P2_ROM_MUX_2D_R_SCL";
33"SMB_RT_CPU0_P0_ROM_R_SCL";
34"SMB_RT_CPU0_P0_ROM_R_SDA";
35"SMB_RT_CPU0_P3_ROM_MUX_2D_R_SCL";
36"SMB_RT_CPU1_P0_ROM_MUX_2D_R_SCL";
37"SMB_RT_CPU1_P0_ROM_MUX_2D_R_SDA";
38"SMB_RT_CPU1_P3_ROM_MUX_2D_R_SCL";
39"SMB_RT_CPU1_P3_ROM_MUX_2D_R_SDA";
40"SMB_RT_CPU1_P1_ROM_MUX_2D_R_SDA";
41"SMB_RT_CPU1_P2_ROM_MUX_2D_R_SDA";
42"SMB_RT_CPU1_P2_ROM_MUX_2D_R_SCL";
43"SMB_RT_CPU0_P3_ROM_MUX_2D_R_SDA";
44"SMB_RT_CPU0_P2_ROM_MUX_2D_R_SDA";
45"SMB_RT_CPU0_P1_ROM_MUX_2D_R_SCL";
46"SMB_RT_CPU0_P1_ROM_MUX_2D_R_SDA";
47"SMB_RT_CPU1_P2_ROM_MUX_2D_R_SCL";
48"RST_SMB_RT_ROM_R1_N";
49"SMB_RT_CPU1_P2_ROM_MUX_2D_SDA";
50"SMB_RT_CPU1_P2_ROM_MUX_2D_SCL";
51"SMB_RT_CPU1_P3_ROM_MUX_2D_SCL";
52"SMB_RT_CPU1_P1_ROM_MUX_2D_SCL";
53"SMB_RT_CPU1_P3_ROM_MUX_2D_SDA";
54"SMB_RT_CPU1_P1_ROM_MUX_2D_SDA";
55"SMB_RT_CPU1_P0_ROM_MUX_2D_SCL";
56"SMB_RT_CPU1_P0_ROM_MUX_2D_SDA";
57"RST_SMB_RT_ROM_N";
58"SMB_RT_CPU1_P2_ROM_MUX_2D_R_SDA";
59"SMB_RT_CPU1_P1_ROM_MUX_2D_R_SCL";
60"SMB_RT_CPU1_P3_ROM_MUX_2D_R_SDA";
61"SMB_RT_CPU1_P3_ROM_MUX_2D_R_SCL";
62"SMB_RT_CPU1_P1_ROM_MUX_2D_R_SDA";
63"SMB_RT_CPU1_P0_ROM_MUX_2D_R_SCL";
64"SMB_RT_CPU1_P0_ROM_MUX_2D_R_SDA";
65"RT_ROM_SMB_MUX_ADDR2";
66"RT_ROM_SMB_MUX_ADDR1";
67"RT_ROM_SMB_MUX_ADDR0";
68"SMB_MUX_RT_ROM_R1_SCL";
69"SMB_MUX_RT_ROM_SCL";
70"SMB_MUX_RT_ROM_R1_SDA";
71"SMB_MUX_RT_ROM_SDA";
72"SMB_RT_CPU0_P2_ROM_MUX_2D_SDA";
73"SMB_RT_CPU0_P2_ROM_MUX_2D_R_SDA";
74"SMB_RT_CPU0_P2_ROM_MUX_2D_SCL";
75"SMB_RT_CPU0_P2_ROM_MUX_2D_R_SCL";
76"SMB_RT_CPU0_P1_ROM_MUX_2D_SCL";
77"SMB_RT_CPU0_P1_ROM_MUX_2D_R_SCL";
78"SMB_RT_CPU0_P3_ROM_MUX_2D_SDA";
79"SMB_RT_CPU0_P3_ROM_MUX_2D_R_SDA";
80"SMB_RT_CPU0_P0_ROM_MUX_2D_SCL";
81"SMB_RT_CPU0_P0_ROM_MUX_2D_R_SCL";
82"SMB_RT_CPU0_P1_ROM_MUX_2D_SDA";
83"SMB_RT_CPU0_P1_ROM_MUX_2D_R_SDA";
84"SMB_RT_CPU0_P0_ROM_MUX_2D_SDA";
85"SMB_RT_CPU0_P0_ROM_MUX_2D_R_SDA";
86"SMB_RT_CPU0_P3_ROM_MUX_2D_SCL";
87"SMB_RT_CPU0_P3_ROM_MUX_2D_R_SCL";
88"RST_SMB_RT_ROM_R1_N";
89"SMB_RT_CPU0_P1_ROM_R_SCL";
90"SMB_RT_CPU0_P1_ROM_R_SDA";
91"SMB_RT_CPU1_P0_ROM_R_SDA";
92"SMB_RT_CPU1_P0_ROM_R_SCL";
93"SMB_RT_CPU1_P1_ROM_R_SCL";
94"SMB_RT_CPU1_P1_ROM_R_SDA";
95"SMB_RT_CPU0_P3_ROM_R_SDA";
96"SMB_RT_CPU0_P2_ROM_R_SDA";
97"SMB_RT_CPU0_P2_ROM_R_SCL";
98"SMB_RT_CPU0_P3_ROM_R_SCL";
99"RT_ROM_SMB_MUX_ADDR2";
100"RT_ROM_SMB_MUX_ADDR1";
101"RT_ROM_SMB_MUX_ADDR0";
102"SMB_RT_CPU1_P3_ROM_R_SDA";
103"SMB_RT_CPU1_P2_ROM_R_SCL";
104"SMB_RT_CPU1_P2_ROM_R_SDA";
105"SMB_RT_CPU1_P3_ROM_R_SCL";
%"UNIVERSAL_GND"
"1","(-8525,875)","0","pure_quanta_power","I1";
;
CDS_LIB"pure_quanta_power"
HDL_POWER"GND";
"A"20;
%"Q_RES"
"1","(-2400,2625)","0","pure_quanta","I104";
;
LOCATION"R1361"
SEC"1"
PACK_TYPE"0201LF"
TOLERANCE"5%"
VALUE"4.7K"
WATTAGE"1/20W"
MATERIAL"CHIP"
SEC_TYPE"0201LF"
CDS_LIB"pure_quanta"
PART_NUMBER"CS24701JE04";
"B"
$PN"2"37;
"A"
$PN"1"18;
%"Q_RES"
"1","(-2400,2575)","0","pure_quanta","I105";
;
LOCATION"R1390"
$SEC"1"
CDS_SEC"1"
PACK_TYPE"0201LF"
VALUE"4.7K"
MATERIAL"CHIP"
WATTAGE"1/20W"
TOLERANCE"5%"
CDS_LIB"pure_quanta"
PART_NUMBER"CS24701JE04";
"B"
$PN"2"36;
"A"
$PN"1"18;
%"Q_RES"
"1","(-2400,2525)","0","pure_quanta","I106";
;
LOCATION"R1393"
$SEC"1"
CDS_SEC"1"
PACK_TYPE"0201LF"
MATERIAL"CHIP"
VALUE"4.7K"
TOLERANCE"5%"
WATTAGE"1/20W"
CDS_LIB"pure_quanta"
PART_NUMBER"CS24701JE04";
"B"
$PN"2"40;
"A"
$PN"1"18;
%"Q_RES"
"1","(-2400,2475)","0","pure_quanta","I107";
;
LOCATION"R1394"
$SEC"1"
CDS_SEC"1"
PACK_TYPE"0201LF"
MATERIAL"CHIP"
VALUE"4.7K"
TOLERANCE"5%"
WATTAGE"1/20W"
CDS_LIB"pure_quanta"
PART_NUMBER"CS24701JE04";
"B"
$PN"2"9;
"A"
$PN"1"18;
%"Q_RES"
"1","(-2400,2425)","0","pure_quanta","I108";
;
LOCATION"R1399"
$SEC"1"
CDS_SEC"1"
PACK_TYPE"0201LF"
MATERIAL"CHIP"
VALUE"4.7K"
TOLERANCE"5%"
WATTAGE"1/20W"
CDS_LIB"pure_quanta"
PART_NUMBER"CS24701JE04";
"B"
$PN"2"39;
"A"
$PN"1"18;
%"Q_RES"
"1","(-2400,2375)","0","pure_quanta","I109";
;
LOCATION"R1402"
$SEC"1"
CDS_SEC"1"
PACK_TYPE"0201LF"
MATERIAL"CHIP"
VALUE"4.7K"
WATTAGE"1/20W"
TOLERANCE"5%"
CDS_LIB"pure_quanta"
PART_NUMBER"CS24701JE04";
"B"
$PN"2"38;
"A"
$PN"1"18;
%"Q_RES"
"1","(-2400,2325)","0","pure_quanta","I110";
;
LOCATION"R1403"
$SEC"1"
CDS_SEC"1"
PACK_TYPE"0201LF"
MATERIAL"CHIP"
VALUE"4.7K"
TOLERANCE"5%"
WATTAGE"1/20W"
CDS_LIB"pure_quanta"
PART_NUMBER"CS24701JE04";
"B"
$PN"2"41;
"A"
$PN"1"18;
%"Q_RES"
"1","(-2400,2275)","0","pure_quanta","I111";
;
LOCATION"R1407"
$SEC"1"
CDS_SEC"1"
VALUE"4.7K"
PACK_TYPE"0201LF"
MATERIAL"CHIP"
TOLERANCE"5%"
WATTAGE"1/20W"
CDS_LIB"pure_quanta"
PART_NUMBER"CS24701JE04";
"B"
$PN"2"42;
"A"
$PN"1"18;
%"P1V0"
"1","(-3025,2975)","0","pure_quanta_power","I112";
;
HDL_POWER"P1V8_CPU1_RT_1D"
CDS_LIB"pure_quanta_power";
"A"18;
%"Q_RES"
"1","(-5550,2600)","0","pure_quanta","I121";
;
LOCATION"R1367"
$SEC"1"
CDS_SEC"1"
VALUE"4.7K"
MATERIAL"CHIP"
PACK_TYPE"0201LF"
TOLERANCE"5%"
WATTAGE"1/20W"
CDS_LIB"pure_quanta"
PART_NUMBER"CS24701JE04";
"B"
$PN"2"17;
"A"
$PN"1"16;
%"Q_RES"
"1","(-5550,2650)","0","pure_quanta","I122";
;
LOCATION"R1366"
$SEC"1"
CDS_SEC"1"
TOLERANCE"5%"
PACK_TYPE"0201LF"
MATERIAL"CHIP"
WATTAGE"1/20W"
VALUE"4.7K"
CDS_LIB"pure_quanta"
PART_NUMBER"CS24701JE04";
"B"
$PN"2"12;
"A"
$PN"1"16;
%"Q_RES"
"1","(-5550,2500)","0","pure_quanta","I123";
;
LOCATION"R1374"
$SEC"1"
CDS_SEC"1"
MATERIAL"CHIP"
VALUE"4.7K"
PACK_TYPE"0201LF"
WATTAGE"1/20W"
TOLERANCE"5%"
CDS_LIB"pure_quanta"
PART_NUMBER"CS24701JE04";
"B"
$PN"2"45;
"A"
$PN"1"16;
%"Q_RES"
"1","(-5550,2550)","0","pure_quanta","I124";
;
LOCATION"R1371"
$SEC"1"
CDS_SEC"1"
VALUE"4.7K"
PACK_TYPE"0201LF"
MATERIAL"CHIP"
WATTAGE"1/20W"
TOLERANCE"5%"
CDS_LIB"pure_quanta"
PART_NUMBER"CS24701JE04";
"B"
$PN"2"46;
"A"
$PN"1"16;
%"Q_RES"
"1","(-5550,2450)","0","pure_quanta","I125";
;
LOCATION"R1375"
$SEC"1"
CDS_SEC"1"
VALUE"4.7K"
MATERIAL"CHIP"
PACK_TYPE"0201LF"
WATTAGE"1/20W"
TOLERANCE"5%"
CDS_LIB"pure_quanta"
PART_NUMBER"CS24701JE04";
"B"
$PN"2"43;
"A"
$PN"1"16;
%"Q_RES"
"1","(-5550,2400)","0","pure_quanta","I126";
;
LOCATION"R1379"
$SEC"1"
CDS_SEC"1"
PACK_TYPE"0201LF"
VALUE"4.7K"
MATERIAL"CHIP"
TOLERANCE"5%"
WATTAGE"1/20W"
CDS_LIB"pure_quanta"
PART_NUMBER"CS24701JE04";
"B"
$PN"2"35;
"A"
$PN"1"16;
%"Q_RES"
"1","(-5550,2350)","0","pure_quanta","I127";
;
LOCATION"R1382"
$SEC"1"
CDS_SEC"1"
VALUE"4.7K"
MATERIAL"CHIP"
PACK_TYPE"0201LF"
WATTAGE"1/20W"
TOLERANCE"5%"
CDS_LIB"pure_quanta"
PART_NUMBER"CS24701JE04";
"B"
$PN"2"44;
"A"
$PN"1"16;
%"Q_RES"
"1","(-5550,2300)","0","pure_quanta","I128";
;
LOCATION"R1383"
$SEC"1"
CDS_SEC"1"
VALUE"4.7K"
MATERIAL"CHIP"
PACK_TYPE"0201LF"
WATTAGE"1/20W"
TOLERANCE"5%"
CDS_LIB"pure_quanta"
PART_NUMBER"CS24701JE04";
"B"
$PN"2"32;
"A"
$PN"1"16;
%"P1V0"
"1","(-6150,2925)","0","pure_quanta_power","I129";
;
HDL_POWER"P1V8_CPU0_RT_1D"
CDS_LIB"pure_quanta_power";
"A"16;
%"P1V0"
"1","(-6400,2100)","0","pure_quanta_power","I13";
;
HDL_POWER"P1V8_CPU0_RT_1D"
CDS_LIB"pure_quanta_power";
"A"21;
%"P1V0"
"1","(-3200,4000)","0","pure_quanta_power","I148";
;
HDL_POWER"P1V8_CPU1_RT_1D"
CDS_LIB"pure_quanta_power";
"A"8;
%"UNIVERSAL_GND"
"1","(-7750,2925)","0","pure_quanta_power","I15";
;
CDS_LIB"pure_quanta_power"
HDL_POWER"GND";
"A"1;
%"Q_RES"
"2","(-7750,3300)","0","pure_quanta","I16";
;
LOCATION"R849"
$SEC"1"
CDS_SEC"1"
PACK_TYPE"0201LF"
WATTAGE"1/20W"
VALUE"10K"
TOLERANCE"1%"
MATERIAL"CHIP"
CDS_LIB"pure_quanta"
PART_NUMBER"CS31001FE17";
"A"
$PN"1"88;
"B"
$PN"2"1;
%"P1V0"
"1","(-6325,3950)","0","pure_quanta_power","I163";
;
HDL_POWER"P1V8_CPU0_RT_1D"
CDS_LIB"pure_quanta_power";
"A"13;
%"Q_RES"
"1","(-5725,3675)","0","pure_quanta","I164";
;
LOCATION"R1410"
$SEC"1"
CDS_SEC"1"
MATERIAL"CHIP"
VALUE"1K"
TOLERANCE"1%"
WATTAGE"1/20W"
PACK_TYPE"0201LF"
CDS_LIB"pure_quanta"
PART_NUMBER"CS21001FE07";
"B"
$PN"2"4;
"A"
$PN"1"13;
%"Q_RES"
"1","(-5725,3625)","0","pure_quanta","I165";
;
LOCATION"R1411"
$SEC"1"
CDS_SEC"1"
PACK_TYPE"0201LF"
MATERIAL"CHIP"
VALUE"1K"
CDS_LIB"pure_quanta"
TOLERANCE"1%"
WATTAGE"1/20W"
PART_NUMBER"CS21001FE07";
"B"
$PN"2"30;
"A"
$PN"1"13;
%"Q_RES"
"1","(-5725,3575)","0","pure_quanta","I166";
;
LOCATION"R1415"
$SEC"1"
CDS_SEC"1"
VALUE"1K"
MATERIAL"CHIP"
PACK_TYPE"0201LF"
WATTAGE"1/20W"
TOLERANCE"1%"
CDS_LIB"pure_quanta"
PART_NUMBER"CS21001FE07";
"B"
$PN"2"5;
"A"
$PN"1"13;
%"Q_RES"
"1","(-5725,3525)","0","pure_quanta","I167";
;
LOCATION"R1418"
$SEC"1"
CDS_SEC"1"
VALUE"1K"
MATERIAL"CHIP"
PACK_TYPE"0201LF"
WATTAGE"1/20W"
TOLERANCE"1%"
CDS_LIB"pure_quanta"
PART_NUMBER"CS21001FE07";
"B"
$PN"2"14;
"A"
$PN"1"13;
%"Q_RES"
"1","(-5725,3475)","0","pure_quanta","I168";
;
LOCATION"R1420"
$SEC"1"
CDS_SEC"1"
VALUE"1K"
MATERIAL"CHIP"
PACK_TYPE"0201LF"
WATTAGE"1/20W"
TOLERANCE"1%"
CDS_LIB"pure_quanta"
PART_NUMBER"CS21001FE07";
"B"
$PN"2"6;
"A"
$PN"1"13;
%"Q_RES"
"1","(-5725,3425)","0","pure_quanta","I169";
;
LOCATION"R1428"
$SEC"1"
CDS_SEC"1"
MATERIAL"CHIP"
VALUE"1K"
PACK_TYPE"0201LF"
WATTAGE"1/20W"
TOLERANCE"1%"
CDS_LIB"pure_quanta"
PART_NUMBER"CS21001FE07";
"B"
$PN"2"7;
"A"
$PN"1"13;
%"Q_RES"
"1","(-5875,1225)","0","pure_quanta","I17";
;
LOCATION"R841"
$SEC"1"
CDS_SEC"1"
MATERIAL"CHIP"
VALUE"1K"
PACK_TYPE"0201LF"
TOLERANCE"1%"
WATTAGE"1/20W"
CDS_LIB"pure_quanta"
PART_NUMBER"CS21001FE07";
"B"
$PN"2"97;
"A"
$PN"1"21;
%"Q_RES"
"1","(-5725,3375)","0","pure_quanta","I170";
;
LOCATION"R1431"
$SEC"1"
CDS_SEC"1"
MATERIAL"CHIP"
VALUE"1K"
PACK_TYPE"0201LF"
WATTAGE"1/20W"
TOLERANCE"1%"
CDS_LIB"pure_quanta"
PART_NUMBER"CS21001FE07";
"B"
$PN"2"31;
"A"
$PN"1"13;
%"Q_RES"
"1","(-5725,3325)","0","pure_quanta","I171";
;
LOCATION"R1432"
$SEC"1"
CDS_SEC"1"
MATERIAL"CHIP"
VALUE"1K"
PACK_TYPE"0201LF"
WATTAGE"1/20W"
TOLERANCE"1%"
CDS_LIB"pure_quanta"
PART_NUMBER"CS21001FE07";
"B"
$PN"2"15;
"A"
$PN"1"13;
%"Q_RES"
"1","(-2575,3600)","0","pure_quanta","I172";
;
LOCATION"R1437"
$SEC"1"
CDS_SEC"1"
VALUE"1K"
MATERIAL"CHIP"
PACK_TYPE"0201LF"
CDS_LIB"pure_quanta"
WATTAGE"1/20W"
TOLERANCE"1%"
PART_NUMBER"CS21001FE07";
"B"
$PN"2"26;
"A"
$PN"1"8;
%"Q_RES"
"1","(-2575,3650)","0","pure_quanta","I173";
;
LOCATION"R1436"
$SEC"1"
CDS_SEC"1"
WATTAGE"1/20W"
TOLERANCE"1%"
VALUE"1K"
MATERIAL"CHIP"
PACK_TYPE"0201LF"
CDS_LIB"pure_quanta"
PART_NUMBER"CS21001FE07";
"B"
$PN"2"25;
"A"
$PN"1"8;
%"Q_RES"
"1","(-2575,3550)","0","pure_quanta","I174";
;
LOCATION"R1448"
$SEC"1"
CDS_SEC"1"
PACK_TYPE"0201LF"
MATERIAL"CHIP"
VALUE"1K"
CDS_LIB"pure_quanta"
TOLERANCE"1%"
WATTAGE"1/20W"
PART_NUMBER"CS21001FE07";
"B"
$PN"2"27;
"A"
$PN"1"8;
%"Q_RES"
"1","(-2575,3500)","0","pure_quanta","I175";
;
LOCATION"R1451"
$SEC"1"
CDS_SEC"1"
PACK_TYPE"0201LF"
MATERIAL"CHIP"
VALUE"1K"
CDS_LIB"pure_quanta"
TOLERANCE"1%"
WATTAGE"1/20W"
PART_NUMBER"CS21001FE07";
"B"
$PN"2"28;
"A"
$PN"1"8;
%"Q_RES"
"1","(-2575,3450)","0","pure_quanta","I176";
;
LOCATION"R1462"
$SEC"1"
CDS_SEC"1"
PACK_TYPE"0201LF"
MATERIAL"CHIP"
VALUE"1K"
CDS_LIB"pure_quanta"
TOLERANCE"1%"
WATTAGE"1/20W"
PART_NUMBER"CS21001FE07";
"B"
$PN"2"29;
"A"
$PN"1"8;
%"Q_RES"
"1","(-2575,3400)","0","pure_quanta","I177";
;
LOCATION"R1463"
$SEC"1"
CDS_SEC"1"
PACK_TYPE"0201LF"
MATERIAL"CHIP"
VALUE"1K"
CDS_LIB"pure_quanta"
TOLERANCE"1%"
WATTAGE"1/20W"
PART_NUMBER"CS21001FE07";
"B"
$PN"2"19;
"A"
$PN"1"8;
%"Q_RES"
"1","(-2575,3350)","0","pure_quanta","I178";
;
LOCATION"R1468"
$SEC"1"
CDS_SEC"1"
PACK_TYPE"0201LF"
MATERIAL"CHIP"
VALUE"1K"
CDS_LIB"pure_quanta"
TOLERANCE"1%"
WATTAGE"1/20W"
PART_NUMBER"CS21001FE07";
"B"
$PN"2"11;
"A"
$PN"1"8;
%"Q_RES"
"1","(-2575,3300)","0","pure_quanta","I179";
;
LOCATION"R1469"
$SEC"1"
CDS_SEC"1"
PACK_TYPE"0201LF"
MATERIAL"CHIP"
VALUE"1K"
CDS_LIB"pure_quanta"
TOLERANCE"1%"
WATTAGE"1/20W"
PART_NUMBER"CS21001FE07";
"B"
$PN"2"10;
"A"
$PN"1"8;
%"Q_RES"
"1","(-5875,1300)","0","pure_quanta","I18";
;
LOCATION"R840"
$SEC"1"
CDS_SEC"1"
MATERIAL"CHIP"
VALUE"1K"
PACK_TYPE"0201LF"
WATTAGE"1/20W"
TOLERANCE"1%"
CDS_LIB"pure_quanta"
PART_NUMBER"CS21001FE07";
"B"
$PN"2"96;
"A"
$PN"1"21;
%"Q_RES"
"1","(-5875,1450)","0","pure_quanta","I19";
;
LOCATION"R838"
$SEC"1"
CDS_SEC"1"
PACK_TYPE"0201LF"
VALUE"1K"
MATERIAL"CHIP"
WATTAGE"1/20W"
TOLERANCE"1%"
CDS_LIB"pure_quanta"
PART_NUMBER"CS21001FE07";
"B"
$PN"2"95;
"A"
$PN"1"21;
%"Q_RES"
"2","(-8525,1300)","0","pure_quanta","I2";
;
LOCATION"R845"
$SEC"1"
CDS_SEC"1"
PACK_TYPE"0201LF"
MATERIAL"CHIP"
VALUE"4.7K"
TOLERANCE"5%"
WATTAGE"1/20W"
CDS_LIB"pure_quanta"
PART_NUMBER"CS24701JE04";
"A"
$PN"1"99;
"B"
$PN"2"20;
%"Q_RES"
"1","(-5875,1375)","0","pure_quanta","I20";
;
LOCATION"R839"
$SEC"1"
CDS_SEC"1"
VALUE"1K"
PACK_TYPE"0201LF"
MATERIAL"CHIP"
TOLERANCE"1%"
WATTAGE"1/20W"
CDS_LIB"pure_quanta"
PART_NUMBER"CS21001FE07";
"B"
$PN"2"98;
"A"
$PN"1"21;
%"Q_RES"
"1","(-5875,1550)","0","pure_quanta","I21";
;
LOCATION"R837"
$SEC"1"
CDS_SEC"1"
VALUE"1K"
MATERIAL"CHIP"
PACK_TYPE"0201LF"
CDS_LIB"pure_quanta"
TOLERANCE"1%"
WATTAGE"1/20W"
PART_NUMBER"CS21001FE07";
"B"
$PN"2"89;
"A"
$PN"1"21;
%"Q_RES"
"1","(-5875,1625)","0","pure_quanta","I22";
;
LOCATION"R836"
$SEC"1"
CDS_SEC"1"
MATERIAL"CHIP"
VALUE"1K"
PACK_TYPE"0201LF"
CDS_LIB"pure_quanta"
WATTAGE"1/20W"
TOLERANCE"1%"
PART_NUMBER"CS21001FE07";
"B"
$PN"2"90;
"A"
$PN"1"21;
%"Q_RES"
"1","(-5875,1700)","0","pure_quanta","I23";
;
LOCATION"R835"
$SEC"1"
CDS_SEC"1"
MATERIAL"CHIP"
VALUE"1K"
PACK_TYPE"0201LF"
TOLERANCE"1%"
WATTAGE"1/20W"
CDS_LIB"pure_quanta"
PART_NUMBER"CS21001FE07";
"B"
$PN"2"33;
"A"
$PN"1"21;
%"Q_RES"
"1","(-5875,1800)","0","pure_quanta","I24";
;
LOCATION"R834"
$SEC"1"
CDS_SEC"1"
TOLERANCE"1%"
MATERIAL"CHIP"
PACK_TYPE"0201LF"
WATTAGE"1/20W"
VALUE"1K"
CDS_LIB"pure_quanta"
PART_NUMBER"CS21001FE07";
"B"
$PN"2"34;
"A"
$PN"1"21;
%"Q_RES"
"2","(-8225,1300)","0","pure_quanta","I3";
;
LOCATION"R846"
$SEC"1"
CDS_SEC"1"
PACK_TYPE"0201LF"
MATERIAL"CHIP"
WATTAGE"1/20W"
TOLERANCE"5%"
VALUE"4.7K"
CDS_LIB"pure_quanta"
PART_NUMBER"CS24701JE04";
"A"
$PN"1"100;
"B"
$PN"2"20;
%"UNIVERSAL_GND"
"1","(-4175,4825)","0","pure_quanta_power","I33";
;
CDS_LIB"pure_quanta_power"
HDL_POWER"GND";
"A"2;
%"Q_RES"
"2","(-8525,2075)","0","pure_quanta","I4";
;
LOCATION"R842"
$SEC"1"
CDS_SEC"1"
MATERIAL"EMPTY"
TOLERANCE"5%"
VALUE"4.7K"
WATTAGE"1/20W"
PACK_TYPE"0201LF"
CDS_LIB"pure_quanta"
PART_NUMBER"CS24701JE04";
"A"
$PN"1"24;
"B"
$PN"2"99;
%"Q_RES"
"1","(-6625,5550)","0","pure_quanta","I42";
;
LOCATION"R848"
$SEC"1"
CDS_SEC"1"
VALUE"0"
MATERIAL"CHIP"
PACK_TYPE"0201LF"
TOLERANCE"5%"
WATTAGE"1/20W"
CDS_LIB"pure_quanta"
PART_NUMBER"CS00001JE10";
"B"
$PN"2"57;
"A"
$PN"1"48;
%"Q_RES"
"1","(-6425,5200)","0","pure_quanta","I43";
;
LOCATION"R807"
$SEC"1"
CDS_SEC"1"
MATERIAL"CHIP"
VALUE"0"
TOLERANCE"5%"
PACK_TYPE"0201LF"
WATTAGE"1/20W"
CDS_LIB"pure_quanta"
PART_NUMBER"CS00001JE10";
"B"
$PN"2"61;
"A"
$PN"1"51;
%"Q_RES"
"1","(-6425,5100)","0","pure_quanta","I44";
;
LOCATION"R809"
$SEC"1"
CDS_SEC"1"
PACK_TYPE"0201LF"
VALUE"0"
TOLERANCE"5%"
MATERIAL"CHIP"
CDS_LIB"pure_quanta"
WATTAGE"1/20W"
PART_NUMBER"CS00001JE10";
"B"
$PN"2"47;
"A"
$PN"1"50;
%"Q_RES"
"1","(-6425,5150)","0","pure_quanta","I45";
;
LOCATION"R808"
$SEC"1"
CDS_SEC"1"
MATERIAL"CHIP"
TOLERANCE"5%"
VALUE"0"
PACK_TYPE"0201LF"
WATTAGE"1/20W"
CDS_LIB"pure_quanta"
PART_NUMBER"CS00001JE10";
"B"
$PN"2"58;
"A"
$PN"1"49;
%"Q_RES"
"1","(-6425,5300)","0","pure_quanta","I46";
;
LOCATION"R805"
$SEC"1"
CDS_SEC"1"
MATERIAL"CHIP"
VALUE"0"
TOLERANCE"5%"
PACK_TYPE"0201LF"
WATTAGE"1/20W"
CDS_LIB"pure_quanta"
PART_NUMBER"CS00001JE10";
"B"
$PN"2"59;
"A"
$PN"1"52;
%"Q_RES"
"1","(-6425,5250)","0","pure_quanta","I47";
;
LOCATION"R806"
$SEC"1"
CDS_SEC"1"
MATERIAL"CHIP"
TOLERANCE"5%"
VALUE"0"
PACK_TYPE"0201LF"
CDS_LIB"pure_quanta"
WATTAGE"1/20W"
PART_NUMBER"CS00001JE10";
"B"
$PN"2"60;
"A"
$PN"1"53;
%"Q_RES"
"1","(-6425,5350)","0","pure_quanta","I48";
;
LOCATION"R803"
$SEC"1"
CDS_SEC"1"
MATERIAL"CHIP"
VALUE"0"
PACK_TYPE"0201LF"
TOLERANCE"5%"
WATTAGE"1/20W"
CDS_LIB"pure_quanta"
PART_NUMBER"CS00001JE10";
"B"
$PN"2"62;
"A"
$PN"1"54;
%"Q_RES"
"1","(-6425,5450)","0","pure_quanta","I49";
;
LOCATION"R801"
SEC"1"
PACK_TYPE"0201LF"
MATERIAL"CHIP"
TOLERANCE"5%"
VALUE"0"
WATTAGE"1/20W"
SEC_TYPE"0201LF"
CDS_LIB"pure_quanta"
PART_NUMBER"CS00001JE10";
"B"
$PN"2"64;
"A"
$PN"1"56;
%"Q_RES"
"2","(-8225,2075)","0","pure_quanta","I5";
;
LOCATION"R843"
$SEC"1"
CDS_SEC"1"
WATTAGE"1/20W"
VALUE"4.7K"
TOLERANCE"5%"
PACK_TYPE"0201LF"
MATERIAL"EMPTY"
CDS_LIB"pure_quanta"
PART_NUMBER"CS24701JE04";
"A"
$PN"1"24;
"B"
$PN"2"100;
%"Q_RES"
"1","(-6425,5400)","0","pure_quanta","I50";
;
LOCATION"R802"
SEC"1"
PACK_TYPE"0201LF"
MATERIAL"CHIP"
TOLERANCE"5%"
VALUE"0"
WATTAGE"1/20W"
SEC_TYPE"0201LF"
CDS_LIB"pure_quanta"
PART_NUMBER"CS00001JE10";
"B"
$PN"2"63;
"A"
$PN"1"55;
%"UNIVERSAL_GND"
"1","(-5575,5900)","0","pure_quanta_power","I54";
;
CDS_LIB"pure_quanta_power"
HDL_POWER"GND";
"A"3;
%"Q_CAP"
"1","(-5575,6200)","2","pure_quanta","I55";
;
LOCATION"C365"
$SEC"1"
CDS_SEC"1"
VALUE"0.1UF"
MATERIAL"X7S"
PACK_TYPE"C0201"
VOLTAGE"10V"
TOLERANCE"10%"
CDS_LIB"pure_quanta"
PART_NUMBER"CH4102K6E00";
"B"
$PN"2"3;
"A"
$PN"1"22;
%"P1V0_AUX"
"1","(-5400,6450)","0","pure_quanta_power","I56";
;
HDL_POWER"P1V8_AUX"
CDS_LIB"pure_quanta_power";
"A"22;
%"P1V0"
"1","(-3075,2025)","0","pure_quanta_power","I57";
;
HDL_POWER"P1V8_CPU1_RT_1D"
CDS_LIB"pure_quanta_power";
"A"23;
%"Q_RES"
"1","(-2550,1150)","0","pure_quanta","I58";
;
LOCATION"R827"
$SEC"1"
CDS_SEC"1"
MATERIAL"CHIP"
VALUE"1K"
PACK_TYPE"0201LF"
CDS_LIB"pure_quanta"
WATTAGE"1/20W"
TOLERANCE"1%"
PART_NUMBER"CS21001FE07";
"B"
$PN"2"103;
"A"
$PN"1"23;
%"Q_RES"
"1","(-2550,1225)","0","pure_quanta","I59";
;
LOCATION"R826"
$SEC"1"
CDS_SEC"1"
VALUE"1K"
MATERIAL"CHIP"
PACK_TYPE"0201LF"
CDS_LIB"pure_quanta"
TOLERANCE"1%"
WATTAGE"1/20W"
PART_NUMBER"CS21001FE07";
"B"
$PN"2"104;
"A"
$PN"1"23;
%"Q_RES"
"1","(-2550,1300)","0","pure_quanta","I60";
;
LOCATION"R812"
$SEC"1"
CDS_SEC"1"
VALUE"1K"
PACK_TYPE"0201LF"
MATERIAL"CHIP"
CDS_LIB"pure_quanta"
WATTAGE"1/20W"
TOLERANCE"1%"
PART_NUMBER"CS21001FE07";
"B"
$PN"2"105;
"A"
$PN"1"23;
%"Q_RES"
"1","(-2550,1375)","0","pure_quanta","I61";
;
LOCATION"R810"
$SEC"1"
CDS_SEC"1"
VALUE"1K"
MATERIAL"CHIP"
PACK_TYPE"0201LF"
CDS_LIB"pure_quanta"
TOLERANCE"1%"
WATTAGE"1/20W"
PART_NUMBER"CS21001FE07";
"B"
$PN"2"102;
"A"
$PN"1"23;
%"Q_RES"
"1","(-2550,1475)","0","pure_quanta","I62";
;
LOCATION"R6734"
$SEC"1"
CDS_SEC"1"
VALUE"1K"
MATERIAL"CHIP"
PACK_TYPE"0201LF"
WATTAGE"1/20W"
TOLERANCE"1%"
CDS_LIB"pure_quanta"
PART_NUMBER"CS21001FE07";
"B"
$PN"2"93;
"A"
$PN"1"23;
%"Q_RES"
"1","(-2550,1550)","0","pure_quanta","I63";
;
LOCATION"R6735"
$SEC"1"
CDS_SEC"1"
MATERIAL"CHIP"
PACK_TYPE"0201LF"
VALUE"1K"
TOLERANCE"1%"
WATTAGE"1/20W"
CDS_LIB"pure_quanta"
PART_NUMBER"CS21001FE07";
"B"
$PN"2"94;
"A"
$PN"1"23;
%"Q_RES"
"1","(-2550,1725)","0","pure_quanta","I64";
;
LOCATION"R6707"
$SEC"1"
CDS_SEC"1"
VALUE"1K"
WATTAGE"1/20W"
TOLERANCE"1%"
PACK_TYPE"0201LF"
MATERIAL"CHIP"
CDS_LIB"pure_quanta"
PART_NUMBER"CS21001FE07";
"B"
$PN"2"91;
"A"
$PN"1"23;
%"Q_RES"
"1","(-2550,1625)","0","pure_quanta","I65";
;
LOCATION"R6706"
$SEC"1"
CDS_SEC"1"
MATERIAL"CHIP"
PACK_TYPE"0201LF"
VALUE"1K"
CDS_LIB"pure_quanta"
WATTAGE"1/20W"
TOLERANCE"1%"
PART_NUMBER"CS21001FE07";
"B"
$PN"2"92;
"A"
$PN"1"23;
%"Q_RES"
"1","(-2775,5100)","0","pure_quanta","I73";
;
LOCATION"R833"
$SEC"1"
CDS_SEC"1"
TOLERANCE"5%"
VALUE"0"
MATERIAL"CHIP"
PACK_TYPE"0201LF"
WATTAGE"1/20W"
CDS_LIB"pure_quanta"
PART_NUMBER"CS00001JE10";
"B"
$PN"2"74;
"A"
$PN"1"75;
%"Q_RES"
"1","(-2775,5200)","0","pure_quanta","I74";
;
LOCATION"R831"
$SEC"1"
CDS_SEC"1"
MATERIAL"CHIP"
VALUE"0"
TOLERANCE"5%"
PACK_TYPE"0201LF"
CDS_LIB"pure_quanta"
WATTAGE"1/20W"
PART_NUMBER"CS00001JE10";
"B"
$PN"2"86;
"A"
$PN"1"87;
%"Q_RES"
"1","(-2775,5150)","0","pure_quanta","I75";
;
LOCATION"R832"
$SEC"1"
CDS_SEC"1"
VALUE"0"
MATERIAL"CHIP"
TOLERANCE"5%"
PACK_TYPE"0201LF"
CDS_LIB"pure_quanta"
WATTAGE"1/20W"
PART_NUMBER"CS00001JE10";
"B"
$PN"2"72;
"A"
$PN"1"73;
%"Q_RES"
"1","(-2775,5350)","0","pure_quanta","I76";
;
LOCATION"R828"
$SEC"1"
CDS_SEC"1"
PACK_TYPE"0201LF"
TOLERANCE"5%"
MATERIAL"CHIP"
VALUE"0"
CDS_LIB"pure_quanta"
WATTAGE"1/20W"
PART_NUMBER"CS00001JE10";
"B"
$PN"2"82;
"A"
$PN"1"83;
%"Q_RES"
"1","(-2775,5300)","0","pure_quanta","I77";
;
LOCATION"R829"
$SEC"1"
CDS_SEC"1"
MATERIAL"CHIP"
VALUE"0"
TOLERANCE"5%"
PACK_TYPE"0201LF"
CDS_LIB"pure_quanta"
WATTAGE"1/20W"
PART_NUMBER"CS00001JE10";
"B"
$PN"2"76;
"A"
$PN"1"77;
%"Q_RES"
"1","(-2775,5250)","0","pure_quanta","I78";
;
LOCATION"R830"
$SEC"1"
CDS_SEC"1"
MATERIAL"CHIP"
VALUE"0"
TOLERANCE"5%"
PACK_TYPE"0201LF"
WATTAGE"1/20W"
CDS_LIB"pure_quanta"
PART_NUMBER"CS00001JE10";
"B"
$PN"2"78;
"A"
$PN"1"79;
%"Q_RES"
"1","(-2775,5400)","0","pure_quanta","I79";
;
LOCATION"R799"
SEC"1"
MATERIAL"CHIP"
PACK_TYPE"0201LF"
VALUE"0"
TOLERANCE"5%"
WATTAGE"1/20W"
SEC_TYPE"0201LF"
CDS_LIB"pure_quanta"
PART_NUMBER"CS00001JE10";
"B"
$PN"2"80;
"A"
$PN"1"81;
%"Q_RES"
"2","(-7875,1300)","0","pure_quanta","I8";
;
LOCATION"R847"
$SEC"1"
CDS_SEC"1"
VALUE"4.7K"
TOLERANCE"5%"
WATTAGE"1/20W"
MATERIAL"CHIP"
PACK_TYPE"0201LF"
CDS_LIB"pure_quanta"
PART_NUMBER"CS24701JE04";
"A"
$PN"1"101;
"B"
$PN"2"20;
%"Q_RES"
"1","(-2775,5450)","0","pure_quanta","I80";
;
LOCATION"R797"
SEC"1"
MATERIAL"CHIP"
PACK_TYPE"0201LF"
VALUE"0"
TOLERANCE"5%"
CDS_LIB"pure_quanta"
SEC_TYPE"0201LF"
WATTAGE"1/20W"
PART_NUMBER"CS00001JE10";
"B"
$PN"2"84;
"A"
$PN"1"85;
%"Q_RES"
"1","(-3025,5700)","0","pure_quanta","I81";
;
LOCATION"R850"
$SEC"1"
CDS_SEC"1"
PACK_TYPE"0201LF"
VALUE"0"
MATERIAL"CHIP"
TOLERANCE"5%"
CDS_LIB"pure_quanta"
WATTAGE"1/20W"
PART_NUMBER"CS00001JE10";
"B"
$PN"2"70;
"A"
$PN"1"71;
%"Q_RES"
"1","(-3025,5650)","0","pure_quanta","I82";
;
LOCATION"R851"
$SEC"1"
CDS_SEC"1"
TOLERANCE"5%"
MATERIAL"CHIP"
PACK_TYPE"0201LF"
VALUE"0"
WATTAGE"1/20W"
CDS_LIB"pure_quanta"
PART_NUMBER"CS00001JE10";
"B"
$PN"2"68;
"A"
$PN"1"69;
%"Q_RES"
"2","(-7875,2050)","0","pure_quanta","I9";
;
LOCATION"R844"
$SEC"1"
CDS_SEC"1"
PACK_TYPE"0201LF"
WATTAGE"1/20W"
TOLERANCE"5%"
VALUE"4.7K"
MATERIAL"EMPTY"
CDS_LIB"pure_quanta"
PART_NUMBER"CS24701JE04";
"A"
$PN"1"24;
"B"
$PN"2"101;
%"TCA9548APWR"
"1","(-4825,5425)","0","pure_quanta","I94";
;
LOCATION"U22"
$SEC"1"
CDS_SEC"1"
VALUE"TCA9548APWR"
MATERIAL"IC"
PART_TYPE"SMLF"
CDS_LIB"pure_quanta"
CDS_LMAN_SYM_OUTLINE"-200,475,200,-475"
NEEDS_NO_SIZE"TRUE"
PART_NUMBER"AL009548K02";
"SD4"
$PN"13"85;
"SC4"
$PN"14"81;
"SD5"
$PN"15"83;
"SC5"
$PN"16"77;
"SD6"
$PN"17"79;
"SC6"
$PN"18"87;
"SD7"
$PN"19"73;
"SC7"
$PN"20"75;
"A2"
$PN"21"65;
"SCL"
$PN"22"69;
"SDA"
$PN"23"71;
"VCC"
$PN"24"22;
"GND"
$PN"12"2;
"SC3"
$PN"11"47;
"SD3"
$PN"10"58;
"SC2"
$PN"9"61;
"SD2"
$PN"8"60;
"SC1"
$PN"7"59;
"SD1"
$PN"6"62;
"SC0"
$PN"5"63;
"SD0"
$PN"4"64;
"RESET# \B"
$PN"3"57;
"A1"
$PN"2"66;
"A0"
$PN"1"67;
%"P1V0_AUX"
"1","(-8525,2500)","0","pure_quanta_power","I95";
;
HDL_POWER"P1V8_AUX"
CDS_LIB"pure_quanta_power";
"A"24;
END.
